# S9S_MB_2U (Grand Teton) — schematic netlist excerpt (pin names and nets, part order shuffled) for the footprints in the layout excerpt that follows; sources: Cadence DE-HDL packaged netlist, KiCad conversion of 03242023_DA0F0TMBIJ0_F0T_Motherboard_J_brd_V01_OCP.brd

C834  Q_CAP_DIFFBUS  DIFF BUS_0.22UF 6.3V 20% X6S  pkg C0201  page 175 : \1\ = P5E_CPU1_PE1_TX_C_DN<1> ; \2\ = P5E_CPU1_PE1_TX_DN<1>
C866  Q_CAP_DIFFBUS  DIFF BUS_0.22UF 6.3V 20% X6S  pkg C0201  page 174 : \1\ = P5E_CPU0_PE1_TX_C_DN<1> ; \2\ = P5E_CPU0_PE1_TX_DN<1>
R4392  Q_RES  33.2 1% CHIP  pkg 0402LF  page 225 : A = H_CPU_ERR0_LVC2_R_N ; B = H_CPU_ERR0_PCH_R_N

(kicad_pcb
	(version 20260206)
	(generator "pcbnew")
	(generator_version "10.0")
	(general
		(thickness 1.6)
		(legacy_teardrops no)
	)
	(paper "A4")
	(title_block
		(title "03242023_DA0F0TMBIJ0_F0T_Motherboard_J_brd_V01_OCP.brd")
		(comment 1 "Grand Teton / footprints 1855-1857 of 6105")
	)
	(layers
		(0 "F.Cu" signal "TOP")
		(4 "In1.Cu" signal "GND")
		(6 "In2.Cu" signal "IN1")
		(8 "In3.Cu" signal "GND1")
		(10 "In4.Cu" signal "IN2")
		(12 "In5.Cu" signal "GND2")
		(14 "In6.Cu" signal "IN3")
		(16 "In7.Cu" signal "GND3")
		(18 "In8.Cu" signal "VCC")
		(20 "In9.Cu" signal "VCC1")
		(22 "In10.Cu" signal "GND4")
		(24 "In11.Cu" signal "IN4")
		(26 "In12.Cu" signal "GND5")
		(28 "In13.Cu" signal "IN5")
		(30 "In14.Cu" signal "GND6")
		(32 "In15.Cu" signal "IN6")
		(34 "In16.Cu" signal "GND7")
		(2 "B.Cu" signal "BOTTOM")
		(9 "F.Adhes" user "F.Adhesive")
		(11 "B.Adhes" user "B.Adhesive")
		(13 "F.Paste" user "Package Geometry/Pastemask Top")
		(15 "B.Paste" user "Package Geometry/Pastemask Bottom")
		(5 "F.SilkS" user "Ref Des/Silkscreen Top")
		(7 "B.SilkS" user "Ref Des/Silkscreen Bottom")
		(1 "F.Mask" user "Board Geometry/Soldermask Top")
		(3 "B.Mask" user "Board Geometry/Soldermask Bottom")
		(17 "Dwgs.User" user "User.Drawings")
		(19 "Cmts.User" user "User.Comments")
		(21 "Eco1.User" user "User.Eco1")
		(23 "Eco2.User" user "User.Eco2")
		(25 "Edge.Cuts" user "Board Geometry/Outline")
		(27 "Margin" user)
		(31 "F.CrtYd" user "Package Geometry/Place Bound Top")
		(29 "B.CrtYd" user "Package Geometry/Place Bound Bottom")
		(35 "F.Fab" user "Ref Des/Assembly Top")
		(33 "B.Fab" user "Ref Des/Assembly Bottom")
	)
	(footprint ""
		(layer "F.Cu")
		(at 150.57247 -92.291916)
		(property "Reference" "R4392"
			(at 0 0 0)
			(layer "F.SilkS")
			(hide yes)
			(effects
				(font
					(size 1.27 1.27)
				)
			)
		)
		(property "Value" ""
			(at 0 0 0)
			(layer "F.Fab")
			(effects
				(font
					(size 1.27 1.27)
				)
			)
		)
		(duplicate_pad_numbers_are_jumpers no)
		(fp_line
			(start -0.7874 -0.4064)
			(end 0.7874 -0.4064)
			(stroke
				(width 0.1524)
				(type default)
			)
			(layer "F.SilkS")
		)
		(fp_line
			(start -0.7874 0.4064)
			(end -0.7874 -0.4064)
			(stroke
				(width 0.1524)
				(type default)
			)
			(layer "F.SilkS")
		)
		(fp_line
			(start 0.7874 -0.4064)
			(end 0.7874 0.4064)
			(stroke
				(width 0.1524)
				(type default)
			)
			(layer "F.SilkS")
		)
		(fp_line
			(start 0.7874 0.4064)
			(end -0.7874 0.4064)
			(stroke
				(width 0.1524)
				(type default)
			)
			(layer "F.SilkS")
		)
		(fp_line
			(start -0.67945 -0.305054)
			(end -0.12065 -0.305054)
			(stroke
				(width 0.1)
				(type default)
			)
			(layer "F.Fab")
		)
		(fp_line
			(start -0.67945 0.3048)
			(end -0.67945 -0.305054)
			(stroke
				(width 0.1)
				(type default)
			)
			(layer "F.Fab")
		)
		(fp_line
			(start -0.12065 -0.305054)
			(end -0.12065 -0.2794)
			(stroke
				(width 0.1)
				(type default)
			)
			(layer "F.Fab")
		)
		(fp_line
			(start -0.12065 -0.2794)
			(end 0.12065 -0.2794)
			(stroke
				(width 0.1)
				(type default)
			)
			(layer "F.Fab")
		)
		(fp_line
			(start -0.12065 0.2794)
			(end -0.12065 0.3048)
			(stroke
				(width 0.1)
				(type default)
			)
			(layer "F.Fab")
		)
		(fp_line
			(start -0.12065 0.3048)
			(end -0.67945 0.3048)
			(stroke
				(width 0.1)
				(type default)
			)
			(layer "F.Fab")
		)
		(fp_line
			(start 0.120396 0.2794)
			(end -0.12065 0.2794)
			(stroke
				(width 0.1)
				(type default)
			)
			(layer "F.Fab")
		)
		(fp_line
			(start 0.120396 0.3048)
			(end 0.120396 0.2794)
			(stroke
				(width 0.1)
				(type default)
			)
			(layer "F.Fab")
		)
		(fp_line
			(start 0.12065 -0.3048)
			(end 0.67945 -0.3048)
			(stroke
				(width 0.1)
				(type default)
			)
			(layer "F.Fab")
		)
		(fp_line
			(start 0.12065 -0.2794)
			(end 0.12065 -0.3048)
			(stroke
				(width 0.1)
				(type default)
			)
			(layer "F.Fab")
		)
		(fp_line
			(start 0.67945 -0.3048)
			(end 0.67945 0.3048)
			(stroke
				(width 0.1)
				(type default)
			)
			(layer "F.Fab")
		)
		(fp_line
			(start 0.67945 0.3048)
			(end 0.120396 0.3048)
			(stroke
				(width 0.1)
				(type default)
			)
			(layer "F.Fab")
		)
		(pad "1" smd circle
			(at -0.40005 0)
			(size 0 0)
			(layers "F.Cu" "F.Mask" "F.Paste")
			(net "H_CPU_ERR0_LVC2_R_N")
		)
		(pad "2" smd circle
			(at 0.40005 0)
			(size 0 0)
			(layers "F.Cu" "F.Mask" "F.Paste")
			(net "H_CPU_ERR0_PCH_R_N")
		)
	)
	(footprint ""
		(layer "F.Cu")
		(at 55.87873 -16.099536 90)
		(property "Reference" "C834"
			(at 0 0 90)
			(layer "F.SilkS")
			(hide yes)
			(effects
				(font
					(size 1.27 1.27)
				)
			)
		)
		(property "Value" ""
			(at 0 0 90)
			(layer "F.Fab")
			(effects
				(font
					(size 1.27 1.27)
				)
			)
		)
		(duplicate_pad_numbers_are_jumpers no)
		(fp_line
			(start 0.299974 -0.150114)
			(end 0.299974 0.150114)
			(stroke
				(width 0.1)
				(type default)
			)
			(layer "F.Fab")
		)
		(fp_line
			(start -0.299974 -0.150114)
			(end 0.299974 -0.150114)
			(stroke
				(width 0.1)
				(type default)
			)
			(layer "F.Fab")
		)
		(fp_line
			(start 0.299974 0.150114)
			(end -0.299974 0.150114)
			(stroke
				(width 0.1)
				(type default)
			)
			(layer "F.Fab")
		)
		(fp_line
			(start -0.299974 0.150114)
			(end -0.299974 -0.150114)
			(stroke
				(width 0.1)
				(type default)
			)
			(layer "F.Fab")
		)
		(pad "1" smd rect
			(at -0.2667 0 90)
			(size 0.3048 0.381)
			(layers "F.Cu" "F.Mask" "F.Paste")
			(net "P5E_CPU1_PE1_TX_C_DN<1>")
		)
		(pad "2" smd rect
			(at 0.2667 0 90)
			(size 0.3048 0.381)
			(layers "F.Cu" "F.Mask" "F.Paste")
			(net "P5E_CPU1_PE1_TX_DN<1>")
		)
	)
	(footprint ""
		(layer "F.Cu")
		(at 430.386236 -16.088614 90)
		(property "Reference" "C866"
			(at 0 0 90)
			(layer "F.SilkS")
			(hide yes)
			(effects
				(font
					(size 1.27 1.27)
				)
			)
		)
		(property "Value" ""
			(at 0 0 90)
			(layer "F.Fab")
			(effects
				(font
					(size 1.27 1.27)
				)
			)
		)
		(duplicate_pad_numbers_are_jumpers no)
		(fp_line
			(start 0.299974 -0.150114)
			(end 0.299974 0.150114)
			(stroke
				(width 0.1)
				(type default)
			)
			(layer "F.Fab")
		)
		(fp_line
			(start -0.299974 -0.150114)
			(end 0.299974 -0.150114)
			(stroke
				(width 0.1)
				(type default)
			)
			(layer "F.Fab")
		)
		(fp_line
			(start 0.299974 0.150114)
			(end -0.299974 0.150114)
			(stroke
				(width 0.1)
				(type default)
			)
			(layer "F.Fab")
		)
		(fp_line
			(start -0.299974 0.150114)
			(end -0.299974 -0.150114)
			(stroke
				(width 0.1)
				(type default)
			)
			(layer "F.Fab")
		)
		(pad "1" smd rect
			(at -0.2667 0 90)
			(size 0.3048 0.381)
			(layers "F.Cu" "F.Mask" "F.Paste")
			(net "P5E_CPU0_PE1_TX_C_DN<1>")
		)
		(pad "2" smd rect
			(at 0.2667 0 90)
			(size 0.3048 0.381)
			(layers "F.Cu" "F.Mask" "F.Paste")
			(net "P5E_CPU0_PE1_TX_DN<1>")
		)
	)
)
